# T6G (Grand Teton) — schematic netlist excerpt (pin names and nets, part order shuffled) for the footprints in the layout excerpt that follows; sources: Cadence DE-HDL packaged netlist, KiCad conversion of 04192023_DAF0TMB3IC0_F0TG_MB_C_brd_V02_OCP.brd

R1632  Q_RES  33 5% CHIP  pkg 0402LF  page 172 : A = HDT_CPU0_HDT_CONN_TESTEN ; B = CPU0_HDT_CONN_TESTEN
C6122  Q_CAP  100NF 50V 10% X7R  pkg C0402  page 188 : A = P5V ; B = GND
PL6506  Q_INDUCTOR  120NH/69A IND  pkg SMLF  page 363 : \1\ = SW_P0V9_RETIMER_CPU0_SW2 ; \2\ = P0V9_CPU0_RT_2D

(kicad_pcb
	(version 20260206)
	(generator "pcbnew")
	(generator_version "10.0")
	(general
		(thickness 1.6)
		(legacy_teardrops no)
	)
	(paper "A4")
	(title_block
		(title "04192023_DAF0TMB3IC0_F0TG_MB_C_brd_V02_OCP.brd")
		(comment 1 "Grand Teton / footprints 571-573 of 8354")
	)
	(layers
		(0 "F.Cu" signal "TOP")
		(4 "In1.Cu" signal "GND")
		(6 "In2.Cu" signal "IN1")
		(8 "In3.Cu" signal "GND1")
		(10 "In4.Cu" signal "IN2")
		(12 "In5.Cu" signal "GND2")
		(14 "In6.Cu" signal "IN3")
		(16 "In7.Cu" signal "GND3")
		(18 "In8.Cu" signal "VCC")
		(20 "In9.Cu" signal "VCC1")
		(22 "In10.Cu" signal "GND4")
		(24 "In11.Cu" signal "IN4")
		(26 "In12.Cu" signal "GND5")
		(28 "In13.Cu" signal "IN5")
		(30 "In14.Cu" signal "GND6")
		(32 "In15.Cu" signal "IN6")
		(34 "In16.Cu" signal "GND7")
		(2 "B.Cu" signal "BOTTOM")
		(9 "F.Adhes" user "F.Adhesive")
		(11 "B.Adhes" user "B.Adhesive")
		(13 "F.Paste" user "Package Geometry/Pastemask Top")
		(15 "B.Paste" user "Package Geometry/Pastemask Bottom")
		(5 "F.SilkS" user "Ref Des/Silkscreen Top")
		(7 "B.SilkS" user "Ref Des/Silkscreen Bottom")
		(1 "F.Mask" user "Board Geometry/Soldermask Top")
		(3 "B.Mask" user "Board Geometry/Soldermask Bottom")
		(17 "Dwgs.User" user "User.Drawings")
		(19 "Cmts.User" user "User.Comments")
		(21 "Eco1.User" user "User.Eco1")
		(23 "Eco2.User" user "User.Eco2")
		(25 "Edge.Cuts" user "Board Geometry/Outline")
		(27 "Margin" user)
		(31 "F.CrtYd" user "Package Geometry/Place Bound Top")
		(29 "B.CrtYd" user "Package Geometry/Place Bound Bottom")
		(35 "F.Fab" user "Ref Des/Assembly Top")
		(33 "B.Fab" user "Ref Des/Assembly Bottom")
	)
	(footprint ""
		(layer "F.Cu")
		(at 172.593 -132.715 90)
		(property "Reference" "C6122"
			(at 0 0 90)
			(layer "F.SilkS")
			(hide yes)
			(effects
				(font
					(size 1.27 1.27)
				)
			)
		)
		(property "Value" ""
			(at 0 0 90)
			(layer "F.Fab")
			(effects
				(font
					(size 1.27 1.27)
				)
			)
		)
		(duplicate_pad_numbers_are_jumpers no)
		(fp_line
			(start 0.7874 -0.4064)
			(end 0.7874 0.4064)
			(stroke
				(width 0.1524)
				(type default)
			)
			(layer "F.SilkS")
		)
		(fp_line
			(start -0.7874 -0.4064)
			(end 0.7874 -0.4064)
			(stroke
				(width 0.1524)
				(type default)
			)
			(layer "F.SilkS")
		)
		(fp_line
			(start 0.7874 0.4064)
			(end -0.7874 0.4064)
			(stroke
				(width 0.1524)
				(type default)
			)
			(layer "F.SilkS")
		)
		(fp_line
			(start -0.7874 0.4064)
			(end -0.7874 -0.4064)
			(stroke
				(width 0.1524)
				(type default)
			)
			(layer "F.SilkS")
		)
		(fp_line
			(start -0.12065 -0.305054)
			(end -0.12065 -0.2794)
			(stroke
				(width 0.1)
				(type default)
			)
			(layer "F.Fab")
		)
		(fp_line
			(start -0.67945 -0.305054)
			(end -0.12065 -0.305054)
			(stroke
				(width 0.1)
				(type default)
			)
			(layer "F.Fab")
		)
		(fp_line
			(start 0.67945 -0.3048)
			(end 0.67945 0.3048)
			(stroke
				(width 0.1)
				(type default)
			)
			(layer "F.Fab")
		)
		(fp_line
			(start 0.12065 -0.3048)
			(end 0.67945 -0.3048)
			(stroke
				(width 0.1)
				(type default)
			)
			(layer "F.Fab")
		)
		(fp_line
			(start 0.12065 -0.2794)
			(end 0.12065 -0.3048)
			(stroke
				(width 0.1)
				(type default)
			)
			(layer "F.Fab")
		)
		(fp_line
			(start -0.12065 -0.2794)
			(end 0.12065 -0.2794)
			(stroke
				(width 0.1)
				(type default)
			)
			(layer "F.Fab")
		)
		(fp_line
			(start 0.120396 0.2794)
			(end -0.12065 0.2794)
			(stroke
				(width 0.1)
				(type default)
			)
			(layer "F.Fab")
		)
		(fp_line
			(start -0.12065 0.2794)
			(end -0.12065 0.3048)
			(stroke
				(width 0.1)
				(type default)
			)
			(layer "F.Fab")
		)
		(fp_line
			(start 0.67945 0.3048)
			(end 0.120396 0.3048)
			(stroke
				(width 0.1)
				(type default)
			)
			(layer "F.Fab")
		)
		(fp_line
			(start 0.120396 0.3048)
			(end 0.120396 0.2794)
			(stroke
				(width 0.1)
				(type default)
			)
			(layer "F.Fab")
		)
		(fp_line
			(start -0.12065 0.3048)
			(end -0.67945 0.3048)
			(stroke
				(width 0.1)
				(type default)
			)
			(layer "F.Fab")
		)
		(fp_line
			(start -0.67945 0.3048)
			(end -0.67945 -0.305054)
			(stroke
				(width 0.1)
				(type default)
			)
			(layer "F.Fab")
		)
		(pad "1" smd circle
			(at -0.40005 0 90)
			(size 0 0)
			(layers "F.Cu" "F.Mask" "F.Paste")
			(net "P5V")
		)
		(pad "2" smd circle
			(at 0.40005 0 90)
			(size 0 0)
			(layers "F.Cu" "F.Mask" "F.Paste")
			(net "GND")
		)
	)
	(footprint ""
		(layer "F.Cu")
		(at 386.211826 -64.3255 180)
		(property "Reference" "R1632"
			(at 0 0 180)
			(layer "F.SilkS")
			(hide yes)
			(effects
				(font
					(size 1.27 1.27)
				)
			)
		)
		(property "Value" ""
			(at 0 0 180)
			(layer "F.Fab")
			(effects
				(font
					(size 1.27 1.27)
				)
			)
		)
		(duplicate_pad_numbers_are_jumpers no)
		(fp_line
			(start 0.7874 0.4064)
			(end -0.7874 0.4064)
			(stroke
				(width 0.1524)
				(type default)
			)
			(layer "F.SilkS")
		)
		(fp_line
			(start 0.7874 -0.4064)
			(end 0.7874 0.4064)
			(stroke
				(width 0.1524)
				(type default)
			)
			(layer "F.SilkS")
		)
		(fp_line
			(start -0.7874 0.4064)
			(end -0.7874 -0.4064)
			(stroke
				(width 0.1524)
				(type default)
			)
			(layer "F.SilkS")
		)
		(fp_line
			(start -0.7874 -0.4064)
			(end 0.7874 -0.4064)
			(stroke
				(width 0.1524)
				(type default)
			)
			(layer "F.SilkS")
		)
		(fp_line
			(start 0.67945 0.3048)
			(end 0.120396 0.3048)
			(stroke
				(width 0.1)
				(type default)
			)
			(layer "F.Fab")
		)
		(fp_line
			(start 0.67945 -0.3048)
			(end 0.67945 0.3048)
			(stroke
				(width 0.1)
				(type default)
			)
			(layer "F.Fab")
		)
		(fp_line
			(start 0.12065 -0.2794)
			(end 0.12065 -0.3048)
			(stroke
				(width 0.1)
				(type default)
			)
			(layer "F.Fab")
		)
		(fp_line
			(start 0.12065 -0.3048)
			(end 0.67945 -0.3048)
			(stroke
				(width 0.1)
				(type default)
			)
			(layer "F.Fab")
		)
		(fp_line
			(start 0.120396 0.3048)
			(end 0.120396 0.2794)
			(stroke
				(width 0.1)
				(type default)
			)
			(layer "F.Fab")
		)
		(fp_line
			(start 0.120396 0.2794)
			(end -0.12065 0.2794)
			(stroke
				(width 0.1)
				(type default)
			)
			(layer "F.Fab")
		)
		(fp_line
			(start -0.12065 0.3048)
			(end -0.67945 0.3048)
			(stroke
				(width 0.1)
				(type default)
			)
			(layer "F.Fab")
		)
		(fp_line
			(start -0.12065 0.2794)
			(end -0.12065 0.3048)
			(stroke
				(width 0.1)
				(type default)
			)
			(layer "F.Fab")
		)
		(fp_line
			(start -0.12065 -0.2794)
			(end 0.12065 -0.2794)
			(stroke
				(width 0.1)
				(type default)
			)
			(layer "F.Fab")
		)
		(fp_line
			(start -0.12065 -0.305054)
			(end -0.12065 -0.2794)
			(stroke
				(width 0.1)
				(type default)
			)
			(layer "F.Fab")
		)
		(fp_line
			(start -0.67945 0.3048)
			(end -0.67945 -0.305054)
			(stroke
				(width 0.1)
				(type default)
			)
			(layer "F.Fab")
		)
		(fp_line
			(start -0.67945 -0.305054)
			(end -0.12065 -0.305054)
			(stroke
				(width 0.1)
				(type default)
			)
			(layer "F.Fab")
		)
		(pad "1" smd circle
			(at -0.40005 0 180)
			(size 0 0)
			(layers "F.Cu" "F.Mask" "F.Paste")
			(net "HDT_CPU0_HDT_CONN_TESTEN")
		)
		(pad "2" smd circle
			(at 0.40005 0 180)
			(size 0 0)
			(layers "F.Cu" "F.Mask" "F.Paste")
			(net "CPU0_HDT_CONN_TESTEN")
		)
	)
	(footprint ""
		(layer "F.Cu")
		(at 453.892666 -390.076944 -90)
		(property "Reference" "PL6506"
			(at 1.075944 -5.747004 90)
			(unlocked yes)
			(layer "F.SilkS")
			(effects
				(font
					(size 0.7874 0.5842)
					(thickness 0.1524)
				)
				(justify left)
			)
		)
		(property "Value" ""
			(at 0 0 270)
			(layer "F.Fab")
			(effects
				(font
					(size 1.27 1.27)
				)
			)
		)
		(duplicate_pad_numbers_are_jumpers no)
		(fp_line
			(start -3.24993 3.24993)
			(end -3.24993 2.2352)
			(stroke
				(width 0.1524)
				(type default)
			)
			(layer "F.SilkS")
		)
		(fp_line
			(start 3.24993 3.24993)
			(end -3.24993 3.24993)
			(stroke
				(width 0.1524)
				(type default)
			)
			(layer "F.SilkS")
		)
		(fp_line
			(start 3.24993 2.2352)
			(end 3.24993 3.24993)
			(stroke
				(width 0.1524)
				(type default)
			)
			(layer "F.SilkS")
		)
		(fp_line
			(start -3.24993 -2.2352)
			(end -3.24993 -3.24993)
			(stroke
				(width 0.1524)
				(type default)
			)
			(layer "F.SilkS")
		)
		(fp_line
			(start -3.24993 -3.24993)
			(end 3.24993 -3.24993)
			(stroke
				(width 0.1524)
				(type default)
			)
			(layer "F.SilkS")
		)
		(fp_line
			(start 3.24993 -3.24993)
			(end 3.24993 -2.2352)
			(stroke
				(width 0.1524)
				(type default)
			)
			(layer "F.SilkS")
		)
		(fp_line
			(start -3.24993 3.24993)
			(end -3.24993 -3.24993)
			(stroke
				(width 0.1)
				(type default)
			)
			(layer "F.Fab")
		)
		(fp_line
			(start 3.24993 3.24993)
			(end -3.24993 3.24993)
			(stroke
				(width 0.1)
				(type default)
			)
			(layer "F.Fab")
		)
		(fp_line
			(start -3.24993 -3.24993)
			(end 3.24993 -3.24993)
			(stroke
				(width 0.1)
				(type default)
			)
			(layer "F.Fab")
		)
		(fp_line
			(start 3.24993 -3.24993)
			(end 3.24993 3.24993)
			(stroke
				(width 0.1)
				(type default)
			)
			(layer "F.Fab")
		)
		(pad "1" smd rect
			(at -2.29997 0 270)
			(size 2.0066 4.2164)
			(layers "F.Cu" "F.Mask" "F.Paste")
			(net "SW_P0V9_RETIMER_CPU0_SW2")
		)
		(pad "2" smd rect
			(at 2.29997 0 270)
			(size 2.0066 4.2164)
			(layers "F.Cu" "F.Mask" "F.Paste")
			(net "P0V9_CPU0_RT_2D")
		)
	)
)
